(kicad_pcb
	(version 20241229)
	(generator "pcbnew")
	(generator_version "9.0")
	(general
		(thickness 1.62)
		(legacy_teardrops no)
	)
	(paper "A3")
	(title_block
		(title "COM Express 7 Baseboard")
		(date "2025-02-04")
		(rev "1.1.2")
		(company "Antmicro Ltd")
		(comment 1 "www.antmicro.com")
		(comment 9 "footprints 741-745 of 802")
	)
	(layers
		(0 "F.Cu" signal)
		(4 "In1.Cu" signal)
		(6 "In2.Cu" signal)
		(8 "In3.Cu" signal)
		(10 "In4.Cu" signal)
		(12 "In5.Cu" signal)
		(14 "In6.Cu" signal)
		(2 "B.Cu" signal)
		(9 "F.Adhes" user "F.Adhesive")
		(11 "B.Adhes" user "B.Adhesive")
		(13 "F.Paste" user)
		(15 "B.Paste" user)
		(5 "F.SilkS" user "F.Silkscreen")
		(7 "B.SilkS" user "B.Silkscreen")
		(1 "F.Mask" user)
		(3 "B.Mask" user)
		(17 "Dwgs.User" user "User.Drawings")
		(19 "Cmts.User" user "User.Comments")
		(21 "Eco1.User" user "User.Eco1")
		(23 "Eco2.User" user "User.Eco2")
		(25 "Edge.Cuts" user)
		(27 "Margin" user)
		(31 "F.CrtYd" user "F.Courtyard")
		(29 "B.CrtYd" user "B.Courtyard")
		(35 "F.Fab" user)
		(33 "B.Fab" user)
	)
	(footprint "antmicro-footprints:R_0402_1005Metric"
		(layer "B.Cu")
		(at 124.702 147.8)
		(descr "Resistor SMD 0402")
		(tags "resistor SMD 0402")
		(property "Reference" "R214"
			(at 0.848 0.41 0)
			(layer "B.SilkS")
			(effects
				(font
					(size 0.7 0.7)
					(thickness 0.15)
				)
				(justify right bottom mirror)
			)
		)
		(property "Value" "R_0R_0402"
			(at -1.011843 -1.772047 0)
			(layer "B.Fab")
			(effects
				(font
					(size 0.7 0.7)
					(thickness 0.15)
				)
				(justify right bottom mirror)
			)
		)
		(property "Datasheet" "https://industrial.panasonic.com/cdbs/www-data/pdf/RDA0000/AOA0000C301.pdf"
			(at 0 0 0)
			(layer "F.Fab")
			(hide yes)
			(effects
				(font
					(size 1.27 1.27)
					(thickness 0.15)
				)
			)
		)
		(property "Author" "Antmicro"
			(at 0 0 0)
			(layer "B.Fab")
			(hide yes)
			(effects
				(font
					(size 1 1)
					(thickness 0.15)
				)
				(justify mirror)
			)
		)
		(property "Current" "1A"
			(at 0 0 0)
			(layer "B.Fab")
			(hide yes)
			(effects
				(font
					(size 1 1)
					(thickness 0.15)
				)
				(justify mirror)
			)
		)
		(property "License" "Apache-2.0"
			(at 0 0 0)
			(layer "B.Fab")
			(hide yes)
			(effects
				(font
					(size 1 1)
					(thickness 0.15)
				)
				(justify mirror)
			)
		)
		(property "MPN" "ERJ2GE0R00X"
			(at 0 0 0)
			(layer "B.Fab")
			(hide yes)
			(effects
				(font
					(size 1 1)
					(thickness 0.15)
				)
				(justify mirror)
			)
		)
		(property "Manufacturer" "Panasonic"
			(at 0 0 0)
			(layer "B.Fab")
			(hide yes)
			(effects
				(font
					(size 1 1)
					(thickness 0.15)
				)
				(justify mirror)
			)
		)
		(property "Public" "False"
			(at 0 0 0)
			(layer "B.Fab")
			(hide yes)
			(effects
				(font
					(size 1 1)
					(thickness 0.15)
				)
				(justify mirror)
			)
		)
		(property "Tolerance" ""
			(at 0 0 0)
			(layer "B.Fab")
			(hide yes)
			(effects
				(font
					(size 1 1)
					(thickness 0.15)
				)
				(justify mirror)
			)
		)
		(property "Val" "0R"
			(at 0 0 0)
			(layer "B.Fab")
			(hide yes)
			(effects
				(font
					(size 1 1)
					(thickness 0.15)
				)
				(justify mirror)
			)
		)
		(sheetname "PCIe redriver")
		(sheetfile "pcie_redriver.kicad_sch")
		(attr smd)
		(fp_rect
			(start -0.925 0.47)
			(end 0.925 -0.47)
			(stroke
				(width 0.05)
				(type default)
			)
			(fill no)
			(layer "B.CrtYd")
		)
		(fp_rect
			(start -0.5 0.25)
			(end 0.5 -0.25)
			(stroke
				(width 0.15)
				(type solid)
			)
			(fill no)
			(layer "B.Fab")
		)
		(pad "1" smd roundrect
			(at -0.48 0)
			(size 0.59 0.64)
			(layers "B.Cu" "B.Mask" "B.Paste")
			(roundrect_rratio 0.25)
			(net 629 "Net-(U39-EN_{I2C})")
			(pintype "passive")
			(teardrops
				(best_length_ratio 0.2)
				(max_length 1)
				(best_width_ratio 0.9)
				(max_width 2)
				(curved_edges yes)
				(filter_ratio 0.9)
				(enabled yes)
				(allow_two_segments yes)
				(prefer_zone_connections yes)
			)
		)
		(pad "2" smd roundrect
			(at 0.48 0)
			(size 0.59 0.64)
			(layers "B.Cu" "B.Mask" "B.Paste")
			(roundrect_rratio 0.25)
			(net 1 "GND")
			(pintype "passive")
			(teardrops
				(best_length_ratio 0.2)
				(max_length 1)
				(best_width_ratio 0.9)
				(max_width 2)
				(curved_edges yes)
				(filter_ratio 0.9)
				(enabled yes)
				(allow_two_segments yes)
				(prefer_zone_connections yes)
			)
		)
	)
	(footprint "antmicro-footprints:R_0402_1005Metric"
		(layer "B.Cu")
		(at 140.05 169.16 -90)
		(descr "Resistor SMD 0402")
		(tags "resistor SMD 0402")
		(property "Reference" "R54"
			(at -3.9 13.5 90)
			(layer "B.SilkS")
			(effects
				(font
					(size 0.7 0.7)
					(thickness 0.15)
				)
				(justify left bottom mirror)
			)
		)
		(property "Value" "R_1k_0402"
			(at -1.011843 -1.772047 90)
			(layer "B.Fab")
			(effects
				(font
					(size 0.7 0.7)
					(thickness 0.15)
				)
				(justify left bottom mirror)
			)
		)
		(property "Datasheet" "https://www.bourns.com/docs/product-datasheets/cr.pdf"
			(at 0 0 270)
			(layer "F.Fab")
			(hide yes)
			(effects
				(font
					(size 1.27 1.27)
					(thickness 0.15)
				)
			)
		)
		(property "Author" "Antmicro"
			(at -29.11 309.21 0)
			(layer "B.Fab")
			(hide yes)
			(effects
				(font
					(size 1 1)
					(thickness 0.15)
				)
				(justify mirror)
			)
		)
		(property "License" "Apache-2.0"
			(at -29.11 309.21 0)
			(layer "B.Fab")
			(hide yes)
			(effects
				(font
					(size 1 1)
					(thickness 0.15)
				)
				(justify mirror)
			)
		)
		(property "MPN" "CR0402-FX-1001GLF"
			(at -29.11 309.21 0)
			(layer "B.Fab")
			(hide yes)
			(effects
				(font
					(size 1 1)
					(thickness 0.15)
				)
				(justify mirror)
			)
		)
		(property "Manufacturer" "Bourns"
			(at -29.11 309.21 0)
			(layer "B.Fab")
			(hide yes)
			(effects
				(font
					(size 1 1)
					(thickness 0.15)
				)
				(justify mirror)
			)
		)
		(property "Public" "False"
			(at -29.11 309.21 0)
			(layer "B.Fab")
			(hide yes)
			(effects
				(font
					(size 1 1)
					(thickness 0.15)
				)
				(justify mirror)
			)
		)
		(property "Tolerance" "1%"
			(at -29.11 309.21 0)
			(layer "B.Fab")
			(hide yes)
			(effects
				(font
					(size 1 1)
					(thickness 0.15)
				)
				(justify mirror)
			)
		)
		(property "Val" "1k"
			(at -29.11 309.21 0)
			(layer "B.Fab")
			(hide yes)
			(effects
				(font
					(size 1 1)
					(thickness 0.15)
				)
				(justify mirror)
			)
		)
		(sheetname "2xSFP+")
		(sheetfile "2xSFP+.kicad_sch")
		(attr smd)
		(fp_rect
			(start -0.925 0.47)
			(end 0.925 -0.47)
			(stroke
				(width 0.05)
				(type default)
			)
			(fill no)
			(layer "B.CrtYd")
		)
		(fp_rect
			(start -0.5 0.25)
			(end 0.5 -0.25)
			(stroke
				(width 0.15)
				(type solid)
			)
			(fill no)
			(layer "B.Fab")
		)
		(pad "1" smd roundrect
			(at -0.48 0 270)
			(size 0.59 0.64)
			(layers "B.Cu" "B.Mask" "B.Paste")
			(roundrect_rratio 0.25)
			(net 896 "Net-(J2B-RX_{LOS})")
			(pintype "passive")
			(teardrops
				(best_length_ratio 0.2)
				(max_length 1)
				(best_width_ratio 0.9)
				(max_width 2)
				(curved_edges yes)
				(filter_ratio 0.9)
				(enabled yes)
				(allow_two_segments yes)
				(prefer_zone_connections yes)
			)
		)
		(pad "2" smd roundrect
			(at 0.48 0 270)
			(size 0.59 0.64)
			(layers "B.Cu" "B.Mask" "B.Paste")
			(roundrect_rratio 0.25)
			(net 2 "+3V3")
			(pintype "passive")
			(teardrops
				(best_length_ratio 0.2)
				(max_length 1)
				(best_width_ratio 0.9)
				(max_width 2)
				(curved_edges yes)
				(filter_ratio 0.9)
				(enabled yes)
				(allow_two_segments yes)
				(prefer_zone_connections yes)
			)
		)
	)
	(footprint "antmicro-footprints:C_0402_1005Metric"
		(layer "B.Cu")
		(at 124.45 157.14 -90)
		(descr "Capacitor SMD 0402")
		(tags "capacitor SMD 0402")
		(property "Reference" "C211"
			(at -1.33 0.55 90)
			(layer "B.SilkS")
			(effects
				(font
					(size 0.7 0.7)
					(thickness 0.15)
				)
				(justify left bottom mirror)
			)
		)
		(property "Value" "C_100n_0402"
			(at -1.022927 -2.155213 90)
			(layer "B.Fab")
			(effects
				(font
					(size 0.7 0.7)
					(thickness 0.15)
				)
				(justify left bottom mirror)
			)
		)
		(property "Datasheet" "https://www.murata.com/products/productdetail?partno=GRM155R61H104KE14%23"
			(at 0 0 270)
			(layer "F.Fab")
			(hide yes)
			(effects
				(font
					(size 1.27 1.27)
					(thickness 0.15)
				)
			)
		)
		(property "Author" "Antmicro"
			(at -32.69 281.59 0)
			(layer "B.Fab")
			(hide yes)
			(effects
				(font
					(size 1 1)
					(thickness 0.15)
				)
				(justify mirror)
			)
		)
		(property "Dielectric" "X5R"
			(at -32.69 281.59 0)
			(layer "B.Fab")
			(hide yes)
			(effects
				(font
					(size 1 1)
					(thickness 0.15)
				)
				(justify mirror)
			)
		)
		(property "License" "Apache-2.0"
			(at -32.69 281.59 0)
			(layer "B.Fab")
			(hide yes)
			(effects
				(font
					(size 1 1)
					(thickness 0.15)
				)
				(justify mirror)
			)
		)
		(property "MPN" "GRM155R61H104KE14D"
			(at -32.69 281.59 0)
			(layer "B.Fab")
			(hide yes)
			(effects
				(font
					(size 1 1)
					(thickness 0.15)
				)
				(justify mirror)
			)
		)
		(property "Manufacturer" "Murata"
			(at -32.69 281.59 0)
			(layer "B.Fab")
			(hide yes)
			(effects
				(font
					(size 1 1)
					(thickness 0.15)
				)
				(justify mirror)
			)
		)
		(property "Public" "False"
			(at -32.69 281.59 0)
			(layer "B.Fab")
			(hide yes)
			(effects
				(font
					(size 1 1)
					(thickness 0.15)
				)
				(justify mirror)
			)
		)
		(property "Val" "100n"
			(at -32.69 281.59 0)
			(layer "B.Fab")
			(hide yes)
			(effects
				(font
					(size 1 1)
					(thickness 0.15)
				)
				(justify mirror)
			)
		)
		(property "Voltage" "50V"
			(at -32.69 281.59 0)
			(layer "B.Fab")
			(hide yes)
			(effects
				(font
					(size 1 1)
					(thickness 0.15)
				)
				(justify mirror)
			)
		)
		(sheetname "2xSFP+")
		(sheetfile "2xSFP+.kicad_sch")
		(attr smd)
		(fp_rect
			(start -0.925 0.47)
			(end 0.925 -0.47)
			(stroke
				(width 0.05)
				(type default)
			)
			(fill no)
			(layer "B.CrtYd")
		)
		(fp_line
			(start -0.494 0.25)
			(end -0.494 -0.248)
			(stroke
				(width 0.15)
				(type solid)
			)
			(layer "B.Fab")
		)
		(fp_line
			(start 0.504 0.25)
			(end -0.494 0.25)
			(stroke
				(width 0.15)
				(type solid)
			)
			(layer "B.Fab")
		)
		(fp_line
			(start -0.494 -0.248)
			(end 0.504 -0.248)
			(stroke
				(width 0.15)
				(type solid)
			)
			(layer "B.Fab")
		)
		(fp_line
			(start 0.504 -0.248)
			(end 0.504 0.25)
			(stroke
				(width 0.15)
				(type solid)
			)
			(layer "B.Fab")
		)
		(pad "1" smd roundrect
			(at -0.48 0 270)
			(size 0.59 0.64)
			(layers "B.Cu" "B.Mask" "B.Paste")
			(roundrect_rratio 0.25)
			(net 53 "/2xSFP+/SH")
			(pintype "passive")
			(teardrops
				(best_length_ratio 0.2)
				(max_length 1)
				(best_width_ratio 0.9)
				(max_width 2)
				(curved_edges yes)
				(filter_ratio 0.9)
				(enabled yes)
				(allow_two_segments yes)
				(prefer_zone_connections yes)
			)
		)
		(pad "2" smd roundrect
			(at 0.48 0 270)
			(size 0.59 0.64)
			(layers "B.Cu" "B.Mask" "B.Paste")
			(roundrect_rratio 0.25)
			(net 1 "GND")
			(pintype "passive")
			(teardrops
				(best_length_ratio 0.2)
				(max_length 1)
				(best_width_ratio 0.9)
				(max_width 2)
				(curved_edges yes)
				(filter_ratio 0.9)
				(enabled yes)
				(allow_two_segments yes)
				(prefer_zone_connections yes)
			)
		)
	)
	(footprint "antmicro-footprints:R_0402_1005Metric"
		(layer "B.Cu")
		(at 144.25 141.06)
		(descr "Resistor SMD 0402")
		(tags "resistor SMD 0402")
		(property "Reference" "R258"
			(at -1.45 5.4 0)
			(layer "B.SilkS")
			(effects
				(font
					(size 0.7 0.7)
					(thickness 0.15)
				)
				(justify right bottom mirror)
			)
		)
		(property "Value" "R_10k_0402"
			(at -1.011843 -1.772047 0)
			(layer "B.Fab")
			(effects
				(font
					(size 0.7 0.7)
					(thickness 0.15)
				)
				(justify right bottom mirror)
			)
		)
		(property "Datasheet" "https://www.bourns.com/docs/product-datasheets/cr.pdf"
			(at 0 0 0)
			(layer "F.Fab")
			(hide yes)
			(effects
				(font
					(size 1.27 1.27)
					(thickness 0.15)
				)
			)
		)
		(property "Author" "Antmicro"
			(at 0 0 0)
			(layer "B.Fab")
			(hide yes)
			(effects
				(font
					(size 1 1)
					(thickness 0.15)
				)
				(justify mirror)
			)
		)
		(property "License" "Apache-2.0"
			(at 0 0 0)
			(layer "B.Fab")
			(hide yes)
			(effects
				(font
					(size 1 1)
					(thickness 0.15)
				)
				(justify mirror)
			)
		)
		(property "MPN" "CR0402-FX-1002GLF"
			(at 0 0 0)
			(layer "B.Fab")
			(hide yes)
			(effects
				(font
					(size 1 1)
					(thickness 0.15)
				)
				(justify mirror)
			)
		)
		(property "Manufacturer" "Bourns"
			(at 0 0 0)
			(layer "B.Fab")
			(hide yes)
			(effects
				(font
					(size 1 1)
					(thickness 0.15)
				)
				(justify mirror)
			)
		)
		(property "Public" "False"
			(at 0 0 0)
			(layer "B.Fab")
			(hide yes)
			(effects
				(font
					(size 1 1)
					(thickness 0.15)
				)
				(justify mirror)
			)
		)
		(property "Tolerance" "1%"
			(at 0 0 0)
			(layer "B.Fab")
			(hide yes)
			(effects
				(font
					(size 1 1)
					(thickness 0.15)
				)
				(justify mirror)
			)
		)
		(property "Val" "10k"
			(at 0 0 0)
			(layer "B.Fab")
			(hide yes)
			(effects
				(font
					(size 1 1)
					(thickness 0.15)
				)
				(justify mirror)
			)
		)
		(sheetname "KR to SFI #1")
		(sheetfile "kr_sfi.kicad_sch")
		(attr smd)
		(fp_rect
			(start -0.925 0.47)
			(end 0.925 -0.47)
			(stroke
				(width 0.05)
				(type default)
			)
			(fill no)
			(layer "B.CrtYd")
		)
		(fp_rect
			(start -0.5 0.25)
			(end 0.5 -0.25)
			(stroke
				(width 0.15)
				(type solid)
			)
			(fill no)
			(layer "B.Fab")
		)
		(pad "1" smd roundrect
			(at -0.48 0)
			(size 0.59 0.64)
			(layers "B.Cu" "B.Mask" "B.Paste")
			(roundrect_rratio 0.25)
			(net 1 "GND")
			(pintype "passive")
			(teardrops
				(best_length_ratio 0.2)
				(max_length 1)
				(best_width_ratio 0.9)
				(max_width 2)
				(curved_edges yes)
				(filter_ratio 0.9)
				(enabled yes)
				(allow_two_segments yes)
				(prefer_zone_connections yes)
			)
		)
		(pad "2" smd roundrect
			(at 0.48 0)
			(size 0.59 0.64)
			(layers "B.Cu" "B.Mask" "B.Paste")
			(roundrect_rratio 0.25)
			(net 654 "Net-(U43C-GPI0)")
			(pintype "passive")
			(teardrops
				(best_length_ratio 0.2)
				(max_length 1)
				(best_width_ratio 0.9)
				(max_width 2)
				(curved_edges yes)
				(filter_ratio 0.9)
				(enabled yes)
				(allow_two_segments yes)
				(prefer_zone_connections yes)
			)
		)
	)
	(footprint "antmicro-footprints:C_0402_1005Metric"
		(layer "B.Cu")
		(at 128.79 133.87)
		(descr "Capacitor SMD 0402")
		(tags "capacitor SMD 0402")
		(property "Reference" "C193"
			(at -4.19 -4.91 0)
			(layer "B.SilkS")
			(effects
				(font
					(size 0.7 0.7)
					(thickness 0.15)
				)
				(justify right bottom mirror)
			)
		)
		(property "Value" "C_100n_0402"
			(at -1.022927 -2.155213 0)
			(layer "B.Fab")
			(effects
				(font
					(size 0.7 0.7)
					(thickness 0.15)
				)
				(justify right bottom mirror)
			)
		)
		(property "Datasheet" "https://www.murata.com/products/productdetail?partno=GRM155R61H104KE14%23"
			(at 0 0 0)
			(layer "F.Fab")
			(hide yes)
			(effects
				(font
					(size 1.27 1.27)
					(thickness 0.15)
				)
			)
		)
		(property "Author" "Antmicro"
			(at 0 0 0)
			(layer "B.Fab")
			(hide yes)
			(effects
				(font
					(size 1 1)
					(thickness 0.15)
				)
				(justify mirror)
			)
		)
		(property "Dielectric" "X5R"
			(at 0 0 0)
			(layer "B.Fab")
			(hide yes)
			(effects
				(font
					(size 1 1)
					(thickness 0.15)
				)
				(justify mirror)
			)
		)
		(property "License" "Apache-2.0"
			(at 0 0 0)
			(layer "B.Fab")
			(hide yes)
			(effects
				(font
					(size 1 1)
					(thickness 0.15)
				)
				(justify mirror)
			)
		)
		(property "MPN" "GRM155R61H104KE14D"
			(at 0 0 0)
			(layer "B.Fab")
			(hide yes)
			(effects
				(font
					(size 1 1)
					(thickness 0.15)
				)
				(justify mirror)
			)
		)
		(property "Manufacturer" "Murata"
			(at 0 0 0)
			(layer "B.Fab")
			(hide yes)
			(effects
				(font
					(size 1 1)
					(thickness 0.15)
				)
				(justify mirror)
			)
		)
		(property "Public" "False"
			(at 0 0 0)
			(layer "B.Fab")
			(hide yes)
			(effects
				(font
					(size 1 1)
					(thickness 0.15)
				)
				(justify mirror)
			)
		)
		(property "Val" "100n"
			(at 0 0 0)
			(layer "B.Fab")
			(hide yes)
			(effects
				(font
					(size 1 1)
					(thickness 0.15)
				)
				(justify mirror)
			)
		)
		(property "Voltage" "50V"
			(at 0 0 0)
			(layer "B.Fab")
			(hide yes)
			(effects
				(font
					(size 1 1)
					(thickness 0.15)
				)
				(justify mirror)
			)
		)
		(sheetname "KR to SFI #2")
		(sheetfile "kr_sfi.kicad_sch")
		(attr smd)
		(fp_rect
			(start -0.925 0.47)
			(end 0.925 -0.47)
			(stroke
				(width 0.05)
				(type default)
			)
			(fill no)
			(layer "B.CrtYd")
		)
		(fp_line
			(start -0.494 -0.248)
			(end 0.504 -0.248)
			(stroke
				(width 0.15)
				(type solid)
			)
			(layer "B.Fab")
		)
		(fp_line
			(start -0.494 0.25)
			(end -0.494 -0.248)
			(stroke
				(width 0.15)
				(type solid)
			)
			(layer "B.Fab")
		)
		(fp_line
			(start 0.504 -0.248)
			(end 0.504 0.25)
			(stroke
				(width 0.15)
				(type solid)
			)
			(layer "B.Fab")
		)
		(fp_line
			(start 0.504 0.25)
			(end -0.494 0.25)
			(stroke
				(width 0.15)
				(type solid)
			)
			(layer "B.Fab")
		)
		(pad "1" smd roundrect
			(at -0.48 0)
			(size 0.59 0.64)
			(layers "B.Cu" "B.Mask" "B.Paste")
			(roundrect_rratio 0.25)
			(net 1 "GND")
			(pintype "passive")
			(teardrops
				(best_length_ratio 0.2)
				(max_length 1)
				(best_width_ratio 0.9)
				(max_width 2)
				(curved_edges yes)
				(filter_ratio 0.9)
				(enabled yes)
				(allow_two_segments yes)
				(prefer_zone_connections yes)
			)
		)
		(pad "2" smd roundrect
			(at 0.48 0)
			(size 0.59 0.64)
			(layers "B.Cu" "B.Mask" "B.Paste")
			(roundrect_rratio 0.25)
			(net 78 "+1V8")
			(pintype "passive")
			(teardrops
				(best_length_ratio 0.2)
				(max_length 1)
				(best_width_ratio 0.9)
				(max_width 2)
				(curved_edges yes)
				(filter_ratio 0.9)
				(enabled yes)
				(allow_two_segments yes)
				(prefer_zone_connections yes)
			)
		)
	)
)
